G04 ================== begin FILE IDENTIFICATION RECORD ==================*
G04 Layout Name:  16368-sb.brd*
G04 Film Name:    L2GND*
G04 File Format:  Gerber RS274X*
G04 File Origin:  Cadence Allegro 16.5-S056*
G04 Origin Date:  Tue Feb 07 09:07:43 2017*
G04 *
G04 Layer:  VIA CLASS/L2GND*
G04 Layer:  PIN/L2GND*
G04 Layer:  ETCH/L2GND*
G04 Layer:  DRAWING FORMAT/LAYER_PCB_STORY*
G04 Layer:  DRAWING FORMAT/LAYER_L2GND*
G04 *
G04 Offset:    (0.00 0.00)*
G04 Mirror:    No*
G04 Mode:      Negative*
G04 Rotation:  0*
G04 FullContactRelief:  No*
G04 UndefLineWidth:     6.00*
G04 ================== end FILE IDENTIFICATION RECORD ====================*
%FSLAX35Y35*MOIN*%
%IR0*IPPOS*OFA0.00000B0.00000*MIA0B0*SFA1.00000B1.00000*%
%ADD15C,.03*%
%ADD13C,.054*%
%ADD16C,.068*%
%AMMACRO11*
4,1,15,.00398,.00044,
.003999,.000208,
.004004,-.000025,
.003996,-.000258,
.00398,-.00044,
.00483,-.00129,
.004897,-.001007,
.004947,-.000721,
.004981,-.000432,
.004997,-.000141,
.004997,.000149,
.00498,.00044,
.004946,.000729,
.004895,.001015,
.00483,.00129,
.00398,.00044,
0.0*
4,1,15,.00044,-.00398,
.000208,-.003999,
-.000025,-.004004,
-.000258,-.003996,
-.00044,-.00398,
-.00129,-.00483,
-.001007,-.004897,
-.000721,-.004947,
-.000432,-.004981,
-.000141,-.004997,
.000149,-.004997,
.00044,-.00498,
.000729,-.004946,
.001015,-.004895,
.00129,-.00483,
.00044,-.00398,
0.0*
4,1,15,-.00398,-.00044,
-.003999,-.000208,
-.004004,.000025,
-.003996,.000258,
-.00398,.00044,
-.00483,.00129,
-.004897,.001007,
-.004947,.000721,
-.004981,.000432,
-.004997,.000141,
-.004997,-.000149,
-.00498,-.00044,
-.004946,-.000729,
-.004895,-.001015,
-.00483,-.00129,
-.00398,-.00044,
0.0*
4,1,15,-.00044,.00398,
-.000208,.003999,
.000025,.004004,
.000258,.003996,
.00044,.00398,
.00129,.00483,
.001007,.004897,
.000721,.004947,
.000432,.004981,
.000141,.004997,
-.000149,.004997,
-.00044,.00498,
-.000729,.004946,
-.001015,.004895,
-.00129,.00483,
-.00044,.00398,
0.0*
%
%ADD11MACRO11*%
%ADD12C,.114*%
%ADD17O,.068X.051*%
%ADD10C,.225*%
%AMMACRO14*
4,1,19,.02172,.00757,
.022123,.006294,
.022452,.004997,
.022705,.003683,
.02288,.002357,
.022979,.001023,
.022999,-.000315,
.022942,-.001652,
.022807,-.002983,
.022595,-.004304,
.022307,-.005611,
.021943,-.006898,
.02172,-.00757,
.02556,-.01142,
.027155,-.006808,
.027924,-.001989,
.027846,.00289,
.026921,.007681,
.02556,.01142,
.02172,.00757,
0.0*
4,1,19,.00757,-.02172,
.006294,-.022123,
.004997,-.022452,
.003683,-.022705,
.002357,-.02288,
.001023,-.022979,
-.000315,-.022999,
-.001652,-.022942,
-.002983,-.022807,
-.004304,-.022595,
-.005611,-.022307,
-.006898,-.021943,
-.00757,-.02172,
-.01142,-.02556,
-.006808,-.027155,
-.001989,-.027924,
.00289,-.027846,
.007681,-.026921,
.01142,-.02556,
.00757,-.02172,
0.0*
4,1,19,-.02172,-.00757,
-.022123,-.006294,
-.022452,-.004997,
-.022705,-.003683,
-.02288,-.002357,
-.022979,-.001023,
-.022999,.000315,
-.022942,.001652,
-.022807,.002983,
-.022595,.004304,
-.022307,.005611,
-.021943,.006898,
-.02172,.00757,
-.02556,.01142,
-.027155,.006808,
-.027924,.001989,
-.027846,-.00289,
-.026921,-.007681,
-.02556,-.01142,
-.02172,-.00757,
0.0*
4,1,19,-.00757,.02172,
-.006294,.022123,
-.004997,.022452,
-.003683,.022705,
-.002357,.02288,
-.001023,.022979,
.000315,.022999,
.001652,.022942,
.002983,.022807,
.004304,.022595,
.005611,.022307,
.006898,.021943,
.00757,.02172,
.01142,.02556,
.006808,.027155,
.001989,.027924,
-.00289,.027846,
-.007681,.026921,
-.01142,.02556,
-.00757,.02172,
0.0*
%
%ADD14MACRO14*%
%ADD18C,.02*%
%ADD19C,.006*%
%ADD22C,.05004*%
%ADD24C,.06404*%
%ADD23C,.11004*%
%ADD21C,.20504*%
%ADD20O,.06402X.04702*%
G75*
%LPD*%
G75*
G36*
G01X-6000Y-6000D02*
X183165D01*
Y67811D01*
X-6000D01*
Y-6000D01*
G37*
%LPC*%
G75*
G36*
G01X174161Y3937D02*
G02X173228Y3004I-933J0D01*
G01X3937D01*
G02X3004Y3937I0J933D01*
G01Y57874D01*
G02X3937Y58807I933J0D01*
G01X173228D01*
G02X174161Y57874I0J-933D01*
G01Y3937D01*
G37*
%LPD*%
G75*
G54D22*
X26890Y46949D03*
G54D24*
X103642Y43898D03*
X127264D03*
G54D23*
X9000Y48000D03*
X164500Y48500D03*
G54D21*
X17717Y19685D03*
X159449D03*
G54D20*
X56418Y46949D03*
G54D15*
X28100Y39300D03*
X34200Y47000D03*
X28100Y55300D03*
X30827Y47067D03*
X109000Y11000D03*
X95400Y12500D03*
X84100Y14900D03*
X81500Y12700D03*
X74200Y21700D03*
X53437Y13900D03*
X71405Y19607D03*
X68500Y13800D03*
X98000Y25500D03*
X69000Y17200D03*
X84700Y26702D03*
X65300Y24437D03*
X65800Y21000D03*
X46000Y25600D03*
X54500Y25500D03*
X98700Y21000D03*
X95300D03*
X85100Y21100D03*
X56200Y21000D03*
X52800D03*
X45250Y35850D03*
X36733Y47067D03*
X111800Y52264D03*
X96000Y55600D03*
X44607Y46831D03*
X39400D03*
X111700Y39600D03*
X52218Y47067D03*
X56000Y55500D03*
X103700Y36400D03*
X39300Y35500D03*
X47200Y47067D03*
X49730Y46821D03*
X76000Y37750D03*
X87700Y43400D03*
X94800Y46800D03*
X93000Y49700D03*
X58000Y38500D03*
X74000Y34900D03*
X133500Y15700D03*
X118300Y19900D03*
X134200Y9000D03*
X131000Y6000D03*
X127500Y52264D03*
X119500Y33900D03*
X127500Y37000D03*
G54D13*
X26890Y46949D03*
G54D16*
X103642Y43898D03*
X127264D03*
G54D11*
X28802Y13285D03*
X24117Y8600D03*
X11317D03*
X6632Y13285D03*
Y26085D03*
X11317Y30770D03*
X24117D03*
X28802Y26085D03*
X20000Y55000D03*
X15000Y45000D03*
X5000Y38000D03*
Y55000D03*
X68750Y24100D03*
X79940Y26850D03*
X70700Y11200D03*
X40100Y21692D03*
X35000Y5000D03*
X41200Y7400D03*
X98200Y16500D03*
X108140Y28132D03*
X87900Y53100D03*
X103655Y52264D03*
X61300Y47250D03*
X88940Y39400D03*
X170534Y13285D03*
X165849Y8600D03*
X153049D03*
X148364Y13285D03*
Y26085D03*
X153049Y30770D03*
X165849D03*
X170534Y26085D03*
X119400Y29800D03*
X143000Y5000D03*
X137000Y12750D03*
X170000Y45000D03*
X135500D03*
X155000D03*
X165000Y55000D03*
X145000D03*
Y36500D03*
X119403Y52264D03*
G54D12*
X9000Y48000D03*
X164500Y48500D03*
G54D10*
X17717Y19685D03*
X159449D03*
G54D17*
X56418Y46949D03*
G54D14*
X32205Y38484D03*
Y55414D03*
X51103Y38484D03*
Y55414D03*
%LPC*%
G75*
G54D18*
G01X-149983Y-76117D02*
Y-156117D01*
G01D02*
X864117D01*
G01X-153983Y-60117D02*
G02I-12000J0D01*
G01X-159133D02*
G02I-6850J0D01*
G01X-165983Y-76117D02*
Y-44117D01*
G01X-149983Y-60117D02*
X-181983D01*
G01X-149983Y-76117D02*
X864117D01*
G01X-149983Y-111617D02*
X864117D01*
G01X76617Y-76117D02*
Y-156117D01*
G01X214117Y-76117D02*
Y-156117D01*
G01X329117Y-76117D02*
Y-156117D01*
G01X496617Y-76117D02*
Y-156117D01*
G01X666617Y-76117D02*
Y-156117D01*
G01X864117Y-76117D02*
Y-156117D01*
G01X892117Y-60117D02*
G02I-12000J0D01*
G01X886967D02*
G02I-6850J0D01*
G01X880117Y-76117D02*
Y-44117D01*
G01X896117Y-60117D02*
X864117D01*
G54D19*
G01X-137600Y-128617D02*
Y-146117D01*
X-128866D01*
G01X-113987Y-136784D02*
X-113113Y-135909D01*
X-112458Y-134451D01*
X-112021Y-132408D01*
X-112458Y-130659D01*
X-113331Y-129492D01*
X-114860Y-128617D01*
X-120755D01*
Y-146117D01*
X-113550D01*
X-112021Y-144951D01*
X-111148Y-143200D01*
X-110711Y-141159D01*
X-111148Y-139117D01*
X-112458Y-137367D01*
X-113987Y-136784D01*
X-120755D01*
G01X-93430Y-130076D02*
X-94740Y-129200D01*
X-96268Y-128617D01*
X-98015D01*
X-99980Y-129492D01*
X-101508Y-130950D01*
X-102600Y-132701D01*
X-103473Y-135617D01*
X-103692Y-138242D01*
X-103255Y-140867D01*
X-102600Y-142617D01*
X-101290Y-144367D01*
X-99761Y-145534D01*
X-98233Y-146117D01*
X-96705D01*
X-95176Y-145534D01*
X-93866Y-144659D01*
X-92774Y-143493D01*
G01X-67600Y-128617D02*
Y-146117D01*
X-58866D01*
G01X-41366D02*
X-50100D01*
Y-128617D01*
X-41366D01*
G01X-44860Y-137075D02*
X-50100D01*
G01X-33036Y-146117D02*
Y-128617D01*
X-28670D01*
X-26923Y-129492D01*
X-25613Y-130659D01*
X-24521Y-132408D01*
X-23648Y-134451D01*
X-23430Y-137367D01*
X-23648Y-140284D01*
X-24521Y-142326D01*
X-25613Y-144076D01*
X-26923Y-145242D01*
X-28670Y-146117D01*
X-33036D01*
G01X10260Y-135909D02*
X8732Y-134742D01*
X7422Y-134451D01*
X5675Y-135034D01*
X4365Y-136200D01*
X3492Y-138242D01*
X3273Y-140284D01*
X3492Y-142326D01*
X4365Y-144076D01*
X5675Y-145534D01*
X7422Y-146117D01*
X8950Y-145534D01*
X10260Y-144367D01*
G01X28197Y-146117D02*
Y-134451D01*
G01Y-136492D02*
X27324Y-135326D01*
X26013Y-134742D01*
X24485Y-134451D01*
X22957Y-135034D01*
X21647Y-136200D01*
X20773Y-137950D01*
X20337Y-140284D01*
X20773Y-142617D01*
X21647Y-144367D01*
X22957Y-145534D01*
X24485Y-146117D01*
X26013Y-145825D01*
X27324Y-144951D01*
X28197Y-143784D01*
G01X38710Y-146117D02*
Y-134451D01*
G01Y-136784D02*
X39802Y-135617D01*
X40894Y-134742D01*
X42422Y-134451D01*
X43513Y-134742D01*
X44824Y-135617D01*
G01X63197Y-128617D02*
Y-146117D01*
G01Y-143493D02*
X62324Y-144951D01*
X61013Y-145825D01*
X59485Y-146117D01*
X57739Y-145534D01*
X56429Y-144076D01*
X55555Y-142326D01*
X55337Y-140284D01*
X55555Y-138242D01*
X56429Y-136492D01*
X57739Y-135034D01*
X59485Y-134451D01*
X61013Y-134742D01*
X62105Y-135326D01*
X63197Y-136492D01*
G01X-77660Y-101117D02*
Y-83617D01*
X-71983Y-98200D01*
X-66306Y-83617D01*
Y-101117D01*
G01X-54483D02*
X-55793Y-100825D01*
X-57103Y-99659D01*
X-57977Y-97617D01*
X-58413Y-95284D01*
X-57977Y-92950D01*
X-57103Y-90909D01*
X-55793Y-89742D01*
X-54483Y-89451D01*
X-53173Y-89742D01*
X-51863Y-90909D01*
X-50990Y-92950D01*
X-50771Y-95284D01*
X-50990Y-97617D01*
X-51863Y-99659D01*
X-53173Y-100825D01*
X-54483Y-101117D01*
G01X-33053Y-83617D02*
Y-101117D01*
G01Y-98493D02*
X-33926Y-99951D01*
X-35237Y-100825D01*
X-36765Y-101117D01*
X-38511Y-100534D01*
X-39821Y-99076D01*
X-40695Y-97326D01*
X-40913Y-95284D01*
X-40695Y-93242D01*
X-39821Y-91492D01*
X-38511Y-90034D01*
X-36765Y-89451D01*
X-35237Y-89742D01*
X-34145Y-90326D01*
X-33053Y-91492D01*
G01X-22758Y-93242D02*
X-15771D01*
X-16426Y-91200D01*
X-17518Y-90034D01*
X-19046Y-89451D01*
X-20575Y-89742D01*
X-21885Y-90617D01*
X-22758Y-92659D01*
X-23195Y-94409D01*
Y-96159D01*
X-22758Y-97909D01*
X-21666Y-99659D01*
X-20356Y-100825D01*
X-18828Y-101117D01*
X-17300Y-100534D01*
X-15771Y-98784D01*
G01X-1983Y-101117D02*
Y-83617D01*
G01X110317Y-146117D02*
Y-128617D01*
X107697Y-132117D01*
G01Y-146117D02*
X112937D01*
G01X123669Y-138826D02*
X125197Y-136784D01*
X126507Y-135617D01*
X128254Y-135034D01*
X129782Y-135617D01*
X130874Y-136784D01*
X131747Y-138534D01*
X131965Y-140575D01*
X131747Y-142326D01*
X130874Y-144076D01*
X129563Y-145534D01*
X128035Y-146117D01*
X126289Y-145534D01*
X124760Y-143784D01*
X123887Y-141159D01*
X123669Y-138242D01*
X124105Y-134451D01*
X124760Y-132408D01*
X125852Y-130367D01*
X127380Y-128909D01*
X128909Y-128617D01*
X130437Y-129200D01*
X131529Y-130659D01*
G01X140514Y-142617D02*
X141823Y-144659D01*
X143570Y-145825D01*
X145535Y-146117D01*
X147282Y-145825D01*
X149029Y-144367D01*
X150120Y-142617D01*
X150339Y-140867D01*
X149902Y-138826D01*
X148374Y-137367D01*
X146845Y-136784D01*
X144880D01*
G01X146845D02*
X148155Y-135909D01*
X149247Y-134451D01*
X149684Y-132701D01*
X149247Y-130950D01*
X148155Y-129492D01*
X146190Y-128617D01*
X144225Y-128909D01*
X142260Y-130076D01*
G01X158669Y-138826D02*
X160197Y-136784D01*
X161507Y-135617D01*
X163254Y-135034D01*
X164782Y-135617D01*
X165874Y-136784D01*
X166747Y-138534D01*
X166965Y-140575D01*
X166747Y-142326D01*
X165874Y-144076D01*
X164563Y-145534D01*
X163035Y-146117D01*
X161289Y-145534D01*
X159760Y-143784D01*
X158887Y-141159D01*
X158669Y-138242D01*
X159105Y-134451D01*
X159760Y-132408D01*
X160852Y-130367D01*
X162380Y-128909D01*
X163909Y-128617D01*
X165437Y-129200D01*
X166529Y-130659D01*
G01X180317Y-146117D02*
X181845Y-145825D01*
X183592Y-144951D01*
X184684Y-143493D01*
X185120Y-141450D01*
X184684Y-139409D01*
X183374Y-137659D01*
X181409Y-136784D01*
X179225D01*
X177915Y-136200D01*
X176823Y-134742D01*
X176387Y-132701D01*
X177042Y-130659D01*
X178570Y-129200D01*
X180317Y-128617D01*
X182063Y-129200D01*
X183592Y-130659D01*
X184247Y-132701D01*
X183810Y-134742D01*
X182719Y-136200D01*
X181409Y-136784D01*
X179225D01*
X177260Y-137659D01*
X175950Y-139409D01*
X175514Y-141450D01*
X175950Y-143493D01*
X177042Y-144951D01*
X178789Y-145825D01*
X180317Y-146117D01*
G01X97200Y-101117D02*
Y-83617D01*
X102440D01*
X104187Y-84492D01*
X105497Y-86534D01*
X105934Y-88867D01*
X105497Y-91200D01*
X104405Y-92950D01*
X102440Y-93826D01*
X97200D01*
G01X123870Y-85076D02*
X122560Y-84200D01*
X121032Y-83617D01*
X119285D01*
X117320Y-84492D01*
X115792Y-85950D01*
X114700Y-87701D01*
X113827Y-90617D01*
X113608Y-93242D01*
X114045Y-95867D01*
X114700Y-97617D01*
X116010Y-99367D01*
X117539Y-100534D01*
X119067Y-101117D01*
X120595D01*
X122124Y-100534D01*
X123434Y-99659D01*
X124526Y-98493D01*
G01X138313Y-91784D02*
X139187Y-90909D01*
X139842Y-89451D01*
X140279Y-87408D01*
X139842Y-85659D01*
X138969Y-84492D01*
X137440Y-83617D01*
X131545D01*
Y-101117D01*
X138750D01*
X140279Y-99951D01*
X141152Y-98200D01*
X141589Y-96159D01*
X141152Y-94117D01*
X139842Y-92367D01*
X138313Y-91784D01*
X131545D01*
G01X147517Y-106950D02*
X160617D01*
G01X166545Y-101117D02*
Y-83617D01*
X176589Y-101117D01*
Y-83617D01*
G01X189067Y-101117D02*
X187320Y-100825D01*
X185792Y-99659D01*
X184482Y-97909D01*
X183608Y-95867D01*
X183172Y-93534D01*
Y-91200D01*
X183608Y-88867D01*
X184482Y-86825D01*
X185792Y-85076D01*
X187320Y-83909D01*
X189067Y-83617D01*
X190813Y-83909D01*
X192342Y-85076D01*
X193652Y-86825D01*
X194526Y-88867D01*
X194962Y-91200D01*
Y-93534D01*
X194526Y-95867D01*
X193652Y-97909D01*
X192342Y-99659D01*
X190813Y-100825D01*
X189067Y-101117D01*
G01X258282Y-143784D02*
X260029Y-145242D01*
X261994Y-146117D01*
X263740D01*
X265487Y-145242D01*
X266797Y-143784D01*
X267452Y-141742D01*
X267015Y-139701D01*
X265924Y-137950D01*
X263959Y-136784D01*
X261339Y-136200D01*
X259810Y-135034D01*
X259155Y-132992D01*
X259592Y-130950D01*
X260684Y-129492D01*
X262212Y-128617D01*
X263740D01*
X265269Y-129200D01*
X266579Y-130659D01*
G01X282113Y-136784D02*
X282987Y-135909D01*
X283642Y-134451D01*
X284079Y-132408D01*
X283642Y-130659D01*
X282769Y-129492D01*
X281240Y-128617D01*
X275345D01*
Y-146117D01*
X282550D01*
X284079Y-144951D01*
X284952Y-143200D01*
X285389Y-141159D01*
X284952Y-139117D01*
X283642Y-137367D01*
X282113Y-136784D01*
X275345D01*
G01X239908Y-83617D02*
X245367Y-101117D01*
X250826Y-83617D01*
G01X267234Y-101117D02*
X258500D01*
Y-83617D01*
X267234D01*
G01X263740Y-92075D02*
X258500D01*
G01X276000Y-101117D02*
Y-83617D01*
X281459D01*
X283205Y-84492D01*
X284297Y-85659D01*
X284734Y-87992D01*
X284297Y-90326D01*
X282987Y-91784D01*
X281459Y-92659D01*
X276000D01*
G01X281459D02*
X284734Y-101117D01*
G01X297867Y-101700D02*
X297430Y-101409D01*
Y-100825D01*
X297867Y-100534D01*
X298304Y-100825D01*
Y-101409D01*
X297867Y-101700D01*
G01X373450Y-128617D02*
Y-146117D01*
X382184D01*
G01X391169Y-131534D02*
X392479Y-129784D01*
X394007Y-128909D01*
X395754Y-128617D01*
X397937Y-129200D01*
X399465Y-130659D01*
X399902Y-132408D01*
X399684Y-134159D01*
X398810Y-135617D01*
X394444Y-138534D01*
X392479Y-140575D01*
X391169Y-143493D01*
X390732Y-146117D01*
X399902D01*
G01X414127Y-137367D02*
X418494D01*
Y-142617D01*
X417184Y-144367D01*
X415655Y-145534D01*
X413472Y-146117D01*
X411289Y-145534D01*
X409760Y-144367D01*
X408450Y-142617D01*
X407577Y-140575D01*
X407140Y-138242D01*
Y-136200D01*
X407577Y-134451D01*
X408450Y-132408D01*
X409760Y-130659D01*
X411070Y-129492D01*
X412817Y-128617D01*
X414345D01*
X416092Y-129200D01*
X417402Y-130367D01*
G01X425295Y-146117D02*
Y-128617D01*
X435339Y-146117D01*
Y-128617D01*
G01X443014Y-146117D02*
Y-128617D01*
X447380D01*
X449127Y-129492D01*
X450437Y-130659D01*
X451529Y-132408D01*
X452402Y-134451D01*
X452620Y-137367D01*
X452402Y-140284D01*
X451529Y-142326D01*
X450437Y-144076D01*
X449127Y-145242D01*
X447380Y-146117D01*
X443014D01*
G01X373450Y-83617D02*
Y-101117D01*
X382184D01*
G01X399247D02*
Y-89451D01*
G01Y-91492D02*
X398374Y-90326D01*
X397063Y-89742D01*
X395535Y-89451D01*
X394007Y-90034D01*
X392697Y-91200D01*
X391823Y-92950D01*
X391387Y-95284D01*
X391823Y-97617D01*
X392697Y-99367D01*
X394007Y-100534D01*
X395535Y-101117D01*
X397063Y-100825D01*
X398374Y-99951D01*
X399247Y-98784D01*
G01X408232Y-106367D02*
X409542Y-106950D01*
X411289Y-106367D01*
X412380Y-105201D01*
X413254Y-103742D01*
X414563Y-99076D01*
X417402Y-89451D01*
G01X410415D02*
X414563Y-99076D01*
G01X427042Y-93242D02*
X434029D01*
X433374Y-91200D01*
X432282Y-90034D01*
X430754Y-89451D01*
X429225Y-89742D01*
X427915Y-90617D01*
X427042Y-92659D01*
X426605Y-94409D01*
Y-96159D01*
X427042Y-97909D01*
X428134Y-99659D01*
X429444Y-100825D01*
X430972Y-101117D01*
X432500Y-100534D01*
X434029Y-98784D01*
G01X444760Y-101117D02*
Y-89451D01*
G01Y-91784D02*
X445852Y-90617D01*
X446944Y-89742D01*
X448472Y-89451D01*
X449563Y-89742D01*
X450874Y-90617D01*
G01X515564Y-101117D02*
Y-83617D01*
X519930D01*
X521677Y-84492D01*
X522987Y-85659D01*
X524079Y-87408D01*
X524952Y-89451D01*
X525170Y-92367D01*
X524952Y-95284D01*
X524079Y-97326D01*
X522987Y-99076D01*
X521677Y-100242D01*
X519930Y-101117D01*
X515564D01*
G01X534592Y-93242D02*
X541579D01*
X540924Y-91200D01*
X539832Y-90034D01*
X538304Y-89451D01*
X536775Y-89742D01*
X535465Y-90617D01*
X534592Y-92659D01*
X534155Y-94409D01*
Y-96159D01*
X534592Y-97909D01*
X535684Y-99659D01*
X536994Y-100825D01*
X538522Y-101117D01*
X540050Y-100534D01*
X541579Y-98784D01*
G01X552092Y-99076D02*
X553184Y-100242D01*
X554712Y-101117D01*
X556022D01*
X557332Y-100534D01*
X558205Y-99659D01*
X558642Y-98493D01*
X558424Y-96742D01*
X557550Y-95867D01*
X553620Y-94117D01*
X552747Y-92075D01*
X553184Y-90617D01*
X554057Y-89742D01*
X555367Y-89451D01*
X556677Y-89742D01*
X557987Y-90617D01*
G01X572867Y-89451D02*
Y-101117D01*
G01Y-84784D02*
X572430Y-84492D01*
Y-83909D01*
X572867Y-83617D01*
X573304Y-83909D01*
Y-84492D01*
X572867Y-84784D01*
G01X587310Y-105492D02*
X588839Y-106659D01*
X590585Y-106950D01*
X592113Y-106659D01*
X593424Y-105201D01*
X594297Y-103159D01*
Y-89451D01*
G01Y-91784D02*
X593424Y-90617D01*
X592113Y-89742D01*
X590585Y-89451D01*
X588839Y-90034D01*
X587747Y-91200D01*
X586873Y-93242D01*
X586437Y-95284D01*
X586655Y-97034D01*
X587529Y-99076D01*
X588839Y-100534D01*
X590585Y-101117D01*
X591895Y-100825D01*
X593424Y-99659D01*
X594297Y-98493D01*
G01X604155Y-101117D02*
Y-89451D01*
G01Y-92367D02*
X605029Y-90909D01*
X606339Y-89742D01*
X608085Y-89451D01*
X609613Y-89742D01*
X610924Y-90909D01*
X611579Y-92950D01*
Y-101117D01*
G01X622092Y-93242D02*
X629079D01*
X628424Y-91200D01*
X627332Y-90034D01*
X625804Y-89451D01*
X624275Y-89742D01*
X622965Y-90617D01*
X622092Y-92659D01*
X621655Y-94409D01*
Y-96159D01*
X622092Y-97909D01*
X623184Y-99659D01*
X624494Y-100825D01*
X626022Y-101117D01*
X627550Y-100534D01*
X629079Y-98784D01*
G01X639810Y-101117D02*
Y-89451D01*
G01Y-91784D02*
X640902Y-90617D01*
X641994Y-89742D01*
X643522Y-89451D01*
X644613Y-89742D01*
X645924Y-90617D01*
G01X559969Y-128617D02*
X568265D01*
X559969Y-146117D01*
X568265D01*
G01X581617D02*
X579870Y-145825D01*
X578342Y-144659D01*
X577032Y-142909D01*
X576158Y-140867D01*
X575722Y-138534D01*
Y-136200D01*
X576158Y-133867D01*
X577032Y-131825D01*
X578342Y-130076D01*
X579870Y-128909D01*
X581617Y-128617D01*
X583363Y-128909D01*
X584892Y-130076D01*
X586202Y-131825D01*
X587076Y-133867D01*
X587512Y-136200D01*
Y-138534D01*
X587076Y-140867D01*
X586202Y-142909D01*
X584892Y-144659D01*
X583363Y-145825D01*
X581617Y-146117D01*
G01X603484D02*
X594750D01*
Y-128617D01*
X603484D01*
G01X599990Y-137075D02*
X594750D01*
G01X686567Y-128617D02*
X684820Y-129200D01*
X683510Y-130659D01*
X682637Y-132408D01*
X681982Y-134742D01*
X681764Y-137367D01*
X681982Y-139992D01*
X682637Y-142326D01*
X683510Y-144076D01*
X684820Y-145534D01*
X686567Y-146117D01*
X688313Y-145534D01*
X689624Y-144076D01*
X690497Y-142326D01*
X691152Y-139992D01*
X691370Y-137367D01*
X691152Y-134742D01*
X690497Y-132408D01*
X689624Y-130659D01*
X688313Y-129200D01*
X686567Y-128617D01*
G01X699919Y-131534D02*
X701229Y-129784D01*
X702757Y-128909D01*
X704504Y-128617D01*
X706687Y-129200D01*
X708215Y-130659D01*
X708652Y-132408D01*
X708434Y-134159D01*
X707560Y-135617D01*
X703194Y-138534D01*
X701229Y-140575D01*
X699919Y-143493D01*
X699482Y-146117D01*
X708652D01*
G01X717637Y-146700D02*
X725497Y-128617D01*
G01X739067D02*
X737320Y-129200D01*
X736010Y-130659D01*
X735137Y-132408D01*
X734482Y-134742D01*
X734264Y-137367D01*
X734482Y-139992D01*
X735137Y-142326D01*
X736010Y-144076D01*
X737320Y-145534D01*
X739067Y-146117D01*
X740813Y-145534D01*
X742124Y-144076D01*
X742997Y-142326D01*
X743652Y-139992D01*
X743870Y-137367D01*
X743652Y-134742D01*
X742997Y-132408D01*
X742124Y-130659D01*
X740813Y-129200D01*
X739067Y-128617D01*
G01X756130Y-146117D02*
X756567Y-142326D01*
X757222Y-139117D01*
X758095Y-136200D01*
X759187Y-132992D01*
X760934Y-128617D01*
X752200D01*
G01X770137Y-146700D02*
X777997Y-128617D01*
G01X787419Y-131534D02*
X788729Y-129784D01*
X790257Y-128909D01*
X792004Y-128617D01*
X794187Y-129200D01*
X795715Y-130659D01*
X796152Y-132408D01*
X795934Y-134159D01*
X795060Y-135617D01*
X790694Y-138534D01*
X788729Y-140575D01*
X787419Y-143493D01*
X786982Y-146117D01*
X796152D01*
G01X809067Y-128617D02*
X807320Y-129200D01*
X806010Y-130659D01*
X805137Y-132408D01*
X804482Y-134742D01*
X804264Y-137367D01*
X804482Y-139992D01*
X805137Y-142326D01*
X806010Y-144076D01*
X807320Y-145534D01*
X809067Y-146117D01*
X810813Y-145534D01*
X812124Y-144076D01*
X812997Y-142326D01*
X813652Y-139992D01*
X813870Y-137367D01*
X813652Y-134742D01*
X812997Y-132408D01*
X812124Y-130659D01*
X810813Y-129200D01*
X809067Y-128617D01*
G01X826567Y-146117D02*
Y-128617D01*
X823947Y-132117D01*
G01Y-146117D02*
X829187D01*
G01X843630D02*
X844067Y-142326D01*
X844722Y-139117D01*
X845595Y-136200D01*
X846687Y-132992D01*
X848434Y-128617D01*
X839700D01*
G01X734264Y-101117D02*
Y-83617D01*
X738630D01*
X740377Y-84492D01*
X741687Y-85659D01*
X742779Y-87408D01*
X743652Y-89451D01*
X743870Y-92367D01*
X743652Y-95284D01*
X742779Y-97326D01*
X741687Y-99076D01*
X740377Y-100242D01*
X738630Y-101117D01*
X734264D01*
G01X760497D02*
Y-89451D01*
G01Y-91492D02*
X759624Y-90326D01*
X758313Y-89742D01*
X756785Y-89451D01*
X755257Y-90034D01*
X753947Y-91200D01*
X753073Y-92950D01*
X752637Y-95284D01*
X753073Y-97617D01*
X753947Y-99367D01*
X755257Y-100534D01*
X756785Y-101117D01*
X758313Y-100825D01*
X759624Y-99951D01*
X760497Y-98784D01*
G01X774067Y-83617D02*
Y-101117D01*
G01X771010Y-89451D02*
X777124D01*
G01X788292Y-93242D02*
X795279D01*
X794624Y-91200D01*
X793532Y-90034D01*
X792004Y-89451D01*
X790475Y-89742D01*
X789165Y-90617D01*
X788292Y-92659D01*
X787855Y-94409D01*
Y-96159D01*
X788292Y-97909D01*
X789384Y-99659D01*
X790694Y-100825D01*
X792222Y-101117D01*
X793750Y-100534D01*
X795279Y-98784D01*
M02*
